# S9S_MB_2U (Grand Teton) — schematic netlist excerpt (pin names and nets, part order shuffled) for the footprints in the layout excerpt that follows; sources: Cadence DE-HDL packaged netlist, KiCad conversion of 03242023_DA0F0TMBIJ0_F0T_Motherboard_J_brd_V01_OCP.brd

D83  Q_LED  IC  pkg SMLF  page 254 : A = LED_PWRGD_PVCCFA_EHV_FIVRA_CPU1 ; C = LED_PWRGD_PVCCFA_EHV_FIVRA_CP_2
R4567  Q_RES  5.11K 1% CHIP  pkg 0402LF  page 250 : A = P3V3_PDB_AUX_ADC ; B = P1V581_PDB_ADC

(kicad_pcb
	(version 20260206)
	(generator "pcbnew")
	(generator_version "10.0")
	(general
		(thickness 1.6)
		(legacy_teardrops no)
	)
	(paper "A4")
	(title_block
		(title "03242023_DA0F0TMBIJ0_F0T_Motherboard_J_brd_V01_OCP.brd")
		(comment 1 "Grand Teton / footprints 1969-1970 of 6105")
	)
	(layers
		(0 "F.Cu" signal "TOP")
		(4 "In1.Cu" signal "GND")
		(6 "In2.Cu" signal "IN1")
		(8 "In3.Cu" signal "GND1")
		(10 "In4.Cu" signal "IN2")
		(12 "In5.Cu" signal "GND2")
		(14 "In6.Cu" signal "IN3")
		(16 "In7.Cu" signal "GND3")
		(18 "In8.Cu" signal "VCC")
		(20 "In9.Cu" signal "VCC1")
		(22 "In10.Cu" signal "GND4")
		(24 "In11.Cu" signal "IN4")
		(26 "In12.Cu" signal "GND5")
		(28 "In13.Cu" signal "IN5")
		(30 "In14.Cu" signal "GND6")
		(32 "In15.Cu" signal "IN6")
		(34 "In16.Cu" signal "GND7")
		(2 "B.Cu" signal "BOTTOM")
		(9 "F.Adhes" user "F.Adhesive")
		(11 "B.Adhes" user "B.Adhesive")
		(13 "F.Paste" user "Package Geometry/Pastemask Top")
		(15 "B.Paste" user "Package Geometry/Pastemask Bottom")
		(5 "F.SilkS" user "Ref Des/Silkscreen Top")
		(7 "B.SilkS" user "Ref Des/Silkscreen Bottom")
		(1 "F.Mask" user "Board Geometry/Soldermask Top")
		(3 "B.Mask" user "Board Geometry/Soldermask Bottom")
		(17 "Dwgs.User" user "User.Drawings")
		(19 "Cmts.User" user "User.Comments")
		(21 "Eco1.User" user "User.Eco1")
		(23 "Eco2.User" user "User.Eco2")
		(25 "Edge.Cuts" user "Board Geometry/Outline")
		(27 "Margin" user)
		(31 "F.CrtYd" user "Package Geometry/Place Bound Top")
		(29 "B.CrtYd" user "Package Geometry/Place Bound Bottom")
		(35 "F.Fab" user "Ref Des/Assembly Top")
		(33 "B.Fab" user "Ref Des/Assembly Bottom")
	)
	(footprint ""
		(layer "F.Cu")
		(at 61.593476 -79.078836)
		(property "Reference" "D83"
			(at -33.022286 34.341308 90)
			(unlocked yes)
			(layer "F.SilkS")
			(effects
				(font
					(size 0.635 0.4064)
					(thickness 0.1524)
				)
				(justify left)
			)
		)
		(property "Value" ""
			(at 0 0 0)
			(layer "F.Fab")
			(effects
				(font
					(size 1.27 1.27)
				)
			)
		)
		(duplicate_pad_numbers_are_jumpers no)
		(fp_line
			(start -0.90678 0.4826)
			(end -0.90678 -0.4699)
			(stroke
				(width 0.1524)
				(type default)
			)
			(layer "F.SilkS")
		)
		(fp_line
			(start -0.89408 -0.4826)
			(end 0.90678 -0.4826)
			(stroke
				(width 0.1524)
				(type default)
			)
			(layer "F.SilkS")
		)
		(fp_line
			(start -0.79248 -0.4826)
			(end 1.03378 -0.4826)
			(stroke
				(width 0.1524)
				(type default)
			)
			(layer "F.SilkS")
		)
		(fp_line
			(start -0.64008 -0.4826)
			(end 1.16078 -0.4826)
			(stroke
				(width 0.1524)
				(type default)
			)
			(layer "F.SilkS")
		)
		(fp_line
			(start 0.90678 -0.4826)
			(end 0.90678 0.4826)
			(stroke
				(width 0.1524)
				(type default)
			)
			(layer "F.SilkS")
		)
		(fp_line
			(start 0.90678 0.4826)
			(end -0.90678 0.4826)
			(stroke
				(width 0.1524)
				(type default)
			)
			(layer "F.SilkS")
		)
		(fp_line
			(start 1.03378 -0.4826)
			(end 1.03378 0.4826)
			(stroke
				(width 0.1524)
				(type default)
			)
			(layer "F.SilkS")
		)
		(fp_line
			(start 1.03378 0.4826)
			(end -0.79248 0.4826)
			(stroke
				(width 0.1524)
				(type default)
			)
			(layer "F.SilkS")
		)
		(fp_line
			(start 1.16078 -0.4826)
			(end 1.16078 0.4826)
			(stroke
				(width 0.1524)
				(type default)
			)
			(layer "F.SilkS")
		)
		(fp_line
			(start 1.16078 0.4826)
			(end -0.64008 0.4826)
			(stroke
				(width 0.1524)
				(type default)
			)
			(layer "F.SilkS")
		)
		(fp_line
			(start -0.499872 -0.249936)
			(end 0.499872 -0.249936)
			(stroke
				(width 0.1)
				(type default)
			)
			(layer "F.Fab")
		)
		(fp_line
			(start -0.499872 0.249936)
			(end -0.499872 -0.249936)
			(stroke
				(width 0.1)
				(type default)
			)
			(layer "F.Fab")
		)
		(fp_line
			(start 0.499872 -0.249936)
			(end 0.499872 0.249936)
			(stroke
				(width 0.1)
				(type default)
			)
			(layer "F.Fab")
		)
		(fp_line
			(start 0.499872 0.249936)
			(end -0.499872 0.249936)
			(stroke
				(width 0.1)
				(type default)
			)
			(layer "F.Fab")
		)
		(pad "A" smd rect
			(at -0.47498 0)
			(size 0.6096 0.7112)
			(layers "F.Cu" "F.Mask" "F.Paste")
			(net "LED_PWRGD_PVCCFA_EHV_FIVRA_CPU1")
		)
		(pad "C" smd rect
			(at 0.47498 0)
			(size 0.6096 0.7112)
			(layers "F.Cu" "F.Mask" "F.Paste")
			(net "LED_PWRGD_PVCCFA_EHV_FIVRA_CP_2")
		)
	)
	(footprint ""
		(layer "F.Cu")
		(at 40.6146 -104.993948 180)
		(property "Reference" "R4567"
			(at 0 0 180)
			(layer "F.SilkS")
			(hide yes)
			(effects
				(font
					(size 1.27 1.27)
				)
			)
		)
		(property "Value" ""
			(at 0 0 180)
			(layer "F.Fab")
			(effects
				(font
					(size 1.27 1.27)
				)
			)
		)
		(duplicate_pad_numbers_are_jumpers no)
		(fp_line
			(start 0.7874 0.4064)
			(end -0.7874 0.4064)
			(stroke
				(width 0.1524)
				(type default)
			)
			(layer "F.SilkS")
		)
		(fp_line
			(start 0.7874 -0.4064)
			(end 0.7874 0.4064)
			(stroke
				(width 0.1524)
				(type default)
			)
			(layer "F.SilkS")
		)
		(fp_line
			(start -0.7874 0.4064)
			(end -0.7874 -0.4064)
			(stroke
				(width 0.1524)
				(type default)
			)
			(layer "F.SilkS")
		)
		(fp_line
			(start -0.7874 -0.4064)
			(end 0.7874 -0.4064)
			(stroke
				(width 0.1524)
				(type default)
			)
			(layer "F.SilkS")
		)
		(fp_line
			(start 0.67945 0.3048)
			(end 0.120396 0.3048)
			(stroke
				(width 0.1)
				(type default)
			)
			(layer "F.Fab")
		)
		(fp_line
			(start 0.67945 -0.3048)
			(end 0.67945 0.3048)
			(stroke
				(width 0.1)
				(type default)
			)
			(layer "F.Fab")
		)
		(fp_line
			(start 0.12065 -0.2794)
			(end 0.12065 -0.3048)
			(stroke
				(width 0.1)
				(type default)
			)
			(layer "F.Fab")
		)
		(fp_line
			(start 0.12065 -0.3048)
			(end 0.67945 -0.3048)
			(stroke
				(width 0.1)
				(type default)
			)
			(layer "F.Fab")
		)
		(fp_line
			(start 0.120396 0.3048)
			(end 0.120396 0.2794)
			(stroke
				(width 0.1)
				(type default)
			)
			(layer "F.Fab")
		)
		(fp_line
			(start 0.120396 0.2794)
			(end -0.12065 0.2794)
			(stroke
				(width 0.1)
				(type default)
			)
			(layer "F.Fab")
		)
		(fp_line
			(start -0.12065 0.3048)
			(end -0.67945 0.3048)
			(stroke
				(width 0.1)
				(type default)
			)
			(layer "F.Fab")
		)
		(fp_line
			(start -0.12065 0.2794)
			(end -0.12065 0.3048)
			(stroke
				(width 0.1)
				(type default)
			)
			(layer "F.Fab")
		)
		(fp_line
			(start -0.12065 -0.2794)
			(end 0.12065 -0.2794)
			(stroke
				(width 0.1)
				(type default)
			)
			(layer "F.Fab")
		)
		(fp_line
			(start -0.12065 -0.305054)
			(end -0.12065 -0.2794)
			(stroke
				(width 0.1)
				(type default)
			)
			(layer "F.Fab")
		)
		(fp_line
			(start -0.67945 0.3048)
			(end -0.67945 -0.305054)
			(stroke
				(width 0.1)
				(type default)
			)
			(layer "F.Fab")
		)
		(fp_line
			(start -0.67945 -0.305054)
			(end -0.12065 -0.305054)
			(stroke
				(width 0.1)
				(type default)
			)
			(layer "F.Fab")
		)
		(pad "1" smd circle
			(at -0.40005 0 180)
			(size 0 0)
			(layers "F.Cu" "F.Mask" "F.Paste")
			(net "P3V3_PDB_AUX_ADC")
		)
		(pad "2" smd circle
			(at 0.40005 0 180)
			(size 0 0)
			(layers "F.Cu" "F.Mask" "F.Paste")
			(net "P1V581_PDB_ADC")
		)
	)
)
